(kicad_pcb
	(version 20241229)
	(generator "pcbnew")
	(generator_version "9.0")
	(general
		(thickness 1.599998)
		(legacy_teardrops no)
	)
	(paper "A4")
	(title_block
		(date "2023-02-12")
		(rev "1.1.5")
		(comment 9 "footprints 29-35 of 473")
	)
	(layers
		(0 "F.Cu" signal)
		(4 "In1.Cu" power "In1.GND")
		(6 "In2.Cu" signal)
		(8 "In3.Cu" power "In3.GND")
		(10 "In4.Cu" power "In4.VCC")
		(12 "In5.Cu" signal)
		(14 "In6.Cu" power "In6.VCC")
		(2 "B.Cu" signal)
		(9 "F.Adhes" user "F.Adhesive")
		(11 "B.Adhes" user "B.Adhesive")
		(13 "F.Paste" user)
		(15 "B.Paste" user)
		(5 "F.SilkS" user "F.Silkscreen")
		(7 "B.SilkS" user "B.Silkscreen")
		(1 "F.Mask" user)
		(3 "B.Mask" user)
		(17 "Dwgs.User" user "User.Drawings")
		(19 "Cmts.User" user "User.Comments")
		(21 "Eco1.User" user "User.Eco1")
		(23 "Eco2.User" user "User.Eco2")
		(25 "Edge.Cuts" user)
		(27 "Margin" user)
		(31 "F.CrtYd" user "F.Courtyard")
		(29 "B.CrtYd" user "B.Courtyard")
		(35 "F.Fab" user)
		(33 "B.Fab" user)
	)
	(footprint "antmicro-footprints:R_0402_1005Metric"
		(layer "F.Cu")
		(at 116.9492 120 180)
		(descr "Resistor SMD 0402")
		(tags "resistor SMD 0402")
		(property "Reference" "R105"
			(at 3.6142 -0.525 180)
			(layer "F.SilkS")
			(effects
				(font
					(size 0.7 0.7)
					(thickness 0.15)
				)
				(justify left bottom)
			)
		)
		(property "Value" "R_10k2_0402"
			(at 0 1.4 180)
			(layer "F.Fab")
			(effects
				(font
					(size 0.7 0.7)
					(thickness 0.15)
				)
				(justify left bottom)
			)
		)
		(property "Description" "10k2 resistor in 0402 package with 1% tolerance"
			(at 0 0 180)
			(layer "F.Fab")
			(hide yes)
			(effects
				(font
					(size 1.27 1.27)
					(thickness 0.15)
				)
			)
		)
		(property "Author" "Antmicro"
			(at 233.8984 240 0)
			(layer "F.Fab")
			(hide yes)
			(effects
				(font
					(size 1 1)
					(thickness 0.15)
				)
			)
		)
		(property "License" "Apache-2.0"
			(at 233.8984 240 0)
			(layer "F.Fab")
			(hide yes)
			(effects
				(font
					(size 1 1)
					(thickness 0.15)
				)
			)
		)
		(property "MPN" "CR0402-FX-1022GLF"
			(at 233.8984 240 0)
			(layer "F.Fab")
			(hide yes)
			(effects
				(font
					(size 1 1)
					(thickness 0.15)
				)
			)
		)
		(property "Manufacturer" "Bourns"
			(at 233.8984 240 0)
			(layer "F.Fab")
			(hide yes)
			(effects
				(font
					(size 1 1)
					(thickness 0.15)
				)
			)
		)
		(property "Tolerance" "1%"
			(at 233.8984 240 0)
			(layer "F.Fab")
			(hide yes)
			(effects
				(font
					(size 1 1)
					(thickness 0.15)
				)
			)
		)
		(property "Val" "10k2"
			(at 233.8984 240 0)
			(layer "F.Fab")
			(hide yes)
			(effects
				(font
					(size 1 1)
					(thickness 0.15)
				)
			)
		)
		(sheetname "Supply")
		(sheetfile "supply.kicad_sch")
		(attr smd)
		(fp_rect
			(start -0.93 -0.47)
			(end 0.93 0.47)
			(stroke
				(width 0.05)
				(type solid)
			)
			(fill no)
			(layer "F.CrtYd")
		)
		(fp_rect
			(start -0.5 -0.25)
			(end 0.5 0.25)
			(stroke
				(width 0.15)
				(type solid)
			)
			(fill no)
			(layer "F.Fab")
		)
		(pad "1" smd roundrect
			(at -0.485 0 180)
			(size 0.59 0.64)
			(layers "F.Cu" "F.Mask" "F.Paste")
			(roundrect_rratio 0.25)
			(net 660 "/Supply/5V0_FB")
			(pintype "passive")
		)
		(pad "2" smd roundrect
			(at 0.485 0 180)
			(size 0.59 0.64)
			(layers "F.Cu" "F.Mask" "F.Paste")
			(roundrect_rratio 0.25)
			(net 5 "GND")
			(pintype "passive")
		)
	)
	(footprint "antmicro-footprints:R_0402_1005Metric"
		(layer "F.Cu")
		(at 190.889171 122.574485 180)
		(descr "Resistor SMD 0402")
		(tags "resistor SMD 0402")
		(property "Reference" "R94"
			(at 0.989171 -1.325515 180)
			(layer "F.SilkS")
			(effects
				(font
					(size 0.7 0.7)
					(thickness 0.15)
				)
				(justify left bottom)
			)
		)
		(property "Value" "R_330R_0402"
			(at 0 1.4 180)
			(layer "F.Fab")
			(effects
				(font
					(size 0.7 0.7)
					(thickness 0.15)
				)
				(justify left bottom)
			)
		)
		(property "Description" "330R resistor in 0402 package with 1% tolerance"
			(at 0 0 180)
			(layer "F.Fab")
			(hide yes)
			(effects
				(font
					(size 1.27 1.27)
					(thickness 0.15)
				)
			)
		)
		(property "Author" "Antmicro"
			(at 381.778342 245.14897 0)
			(layer "F.Fab")
			(hide yes)
			(effects
				(font
					(size 1 1)
					(thickness 0.15)
				)
			)
		)
		(property "License" "Apache-2.0"
			(at 381.778342 245.14897 0)
			(layer "F.Fab")
			(hide yes)
			(effects
				(font
					(size 1 1)
					(thickness 0.15)
				)
			)
		)
		(property "MPN" "CR0402-FX-3300GLF"
			(at 381.778342 245.14897 0)
			(layer "F.Fab")
			(hide yes)
			(effects
				(font
					(size 1 1)
					(thickness 0.15)
				)
			)
		)
		(property "Manufacturer" "Bourns"
			(at 381.778342 245.14897 0)
			(layer "F.Fab")
			(hide yes)
			(effects
				(font
					(size 1 1)
					(thickness 0.15)
				)
			)
		)
		(property "Tolerance" "1%"
			(at 381.778342 245.14897 0)
			(layer "F.Fab")
			(hide yes)
			(effects
				(font
					(size 1 1)
					(thickness 0.15)
				)
			)
		)
		(property "Val" "330R"
			(at 381.778342 245.14897 0)
			(layer "F.Fab")
			(hide yes)
			(effects
				(font
					(size 1 1)
					(thickness 0.15)
				)
			)
		)
		(sheetname "Supply")
		(sheetfile "supply.kicad_sch")
		(attr smd)
		(fp_rect
			(start -0.93 -0.47)
			(end 0.93 0.47)
			(stroke
				(width 0.05)
				(type solid)
			)
			(fill no)
			(layer "F.CrtYd")
		)
		(fp_rect
			(start -0.5 -0.25)
			(end 0.5 0.25)
			(stroke
				(width 0.15)
				(type solid)
			)
			(fill no)
			(layer "F.Fab")
		)
		(pad "1" smd roundrect
			(at -0.485 0 180)
			(size 0.59 0.64)
			(layers "F.Cu" "F.Mask" "F.Paste")
			(roundrect_rratio 0.25)
			(net 229 "Net-(PWR1-Pad2)")
			(pintype "passive")
		)
		(pad "2" smd roundrect
			(at 0.485 0 180)
			(size 0.59 0.64)
			(layers "F.Cu" "F.Mask" "F.Paste")
			(roundrect_rratio 0.25)
			(net 5 "GND")
			(pintype "passive")
		)
	)
	(footprint "antmicro-footprints:TP_SMD_1mm"
		(layer "F.Cu")
		(at 135 101.124)
		(property "Reference" "TP14"
			(at -0.1 -0.324 90)
			(layer "F.SilkS")
			(effects
				(font
					(size 0.7 0.7)
					(thickness 0.15)
				)
				(justify left bottom)
			)
		)
		(property "Value" "TP_1mm_SMD"
			(at 0 1.4 0)
			(layer "F.Fab")
			(effects
				(font
					(size 0.7 0.7)
					(thickness 0.15)
				)
				(justify left bottom)
			)
		)
		(property "Description" "Test Point 1mm"
			(at 0 0 0)
			(layer "F.Fab")
			(hide yes)
			(effects
				(font
					(size 1.27 1.27)
					(thickness 0.15)
				)
			)
		)
		(property "Author" "Antmicro"
			(at 0 0 0)
			(layer "F.Fab")
			(hide yes)
			(effects
				(font
					(size 1 1)
					(thickness 0.15)
				)
			)
		)
		(property "License" "Apache-2.0"
			(at 0 0 0)
			(layer "F.Fab")
			(hide yes)
			(effects
				(font
					(size 1 1)
					(thickness 0.15)
				)
			)
		)
		(property "MPN" ""
			(at 0 0 0)
			(layer "F.Fab")
			(hide yes)
			(effects
				(font
					(size 1 1)
					(thickness 0.15)
				)
			)
		)
		(property "Manufacturer" ""
			(at 0 0 0)
			(layer "F.Fab")
			(hide yes)
			(effects
				(font
					(size 1 1)
					(thickness 0.15)
				)
			)
		)
		(sheetname "Supply")
		(sheetfile "supply.kicad_sch")
		(attr exclude_from_pos_files)
		(pad "1" smd circle
			(at 0 0)
			(size 1 1)
			(layers "F.Cu" "F.Mask")
			(net 459 "3V3_SYS")
			(pinfunction "1")
			(pintype "passive")
		)
	)
	(footprint "antmicro-footprints:C_0402_1005Metric"
		(layer "F.Cu")
		(at 110.235528 116.747157 180)
		(descr "Capacitor SMD 0402")
		(tags "capacitor SMD 0402")
		(property "Reference" "C130"
			(at 2.735528 -3.252843 225)
			(layer "F.SilkS")
			(effects
				(font
					(size 0.7 0.7)
					(thickness 0.15)
				)
				(justify left bottom)
			)
		)
		(property "Value" "C_10n_0402"
			(at 0 1.4 180)
			(layer "F.Fab")
			(effects
				(font
					(size 0.7 0.7)
					(thickness 0.15)
				)
				(justify left bottom)
			)
		)
		(property "Description" " "
			(at 0 0 180)
			(layer "F.Fab")
			(hide yes)
			(effects
				(font
					(size 1.27 1.27)
					(thickness 0.15)
				)
			)
		)
		(property "Author" "Antmicro"
			(at 220.471056 233.494314 0)
			(layer "F.Fab")
			(hide yes)
			(effects
				(font
					(size 1 1)
					(thickness 0.15)
				)
			)
		)
		(property "Dielectric" "X7R"
			(at 220.471056 233.494314 0)
			(layer "F.Fab")
			(hide yes)
			(effects
				(font
					(size 1 1)
					(thickness 0.15)
				)
			)
		)
		(property "License" "Apache-2.0"
			(at 220.471056 233.494314 0)
			(layer "F.Fab")
			(hide yes)
			(effects
				(font
					(size 1 1)
					(thickness 0.15)
				)
			)
		)
		(property "MPN" "GRM155R71H103KA88D"
			(at 220.471056 233.494314 0)
			(layer "F.Fab")
			(hide yes)
			(effects
				(font
					(size 1 1)
					(thickness 0.15)
				)
			)
		)
		(property "Manufacturer" "Murata"
			(at 220.471056 233.494314 0)
			(layer "F.Fab")
			(hide yes)
			(effects
				(font
					(size 1 1)
					(thickness 0.15)
				)
			)
		)
		(property "Val" "10n"
			(at 220.471056 233.494314 0)
			(layer "F.Fab")
			(hide yes)
			(effects
				(font
					(size 1 1)
					(thickness 0.15)
				)
			)
		)
		(property "Voltage" "50V"
			(at 220.471056 233.494314 0)
			(layer "F.Fab")
			(hide yes)
			(effects
				(font
					(size 1 1)
					(thickness 0.15)
				)
			)
		)
		(sheetname "Supply")
		(sheetfile "supply.kicad_sch")
		(attr smd)
		(fp_rect
			(start -0.94 -0.47)
			(end 0.94 0.47)
			(stroke
				(width 0.05)
				(type solid)
			)
			(fill no)
			(layer "F.CrtYd")
		)
		(fp_rect
			(start -0.499 -0.249)
			(end 0.499 0.249)
			(stroke
				(width 0.15)
				(type solid)
			)
			(fill no)
			(layer "F.Fab")
		)
		(pad "1" smd roundrect
			(at -0.484 0 180)
			(size 0.59 0.64)
			(layers "F.Cu" "F.Mask" "F.Paste")
			(roundrect_rratio 0.25)
			(net 39 "Net-(IC2-SS{slash}TR)")
			(pintype "passive")
		)
		(pad "2" smd roundrect
			(at 0.484 0 180)
			(size 0.59 0.64)
			(layers "F.Cu" "F.Mask" "F.Paste")
			(roundrect_rratio 0.25)
			(net 5 "GND")
			(pintype "passive")
		)
	)
	(footprint "antmicro-footprints:C_0402_1005Metric"
		(layer "F.Cu")
		(at 118.8492 116.975 180)
		(descr "Capacitor SMD 0402")
		(tags "capacitor SMD 0402")
		(property "Reference" "C129"
			(at 0.9492 -3.225 180)
			(layer "F.SilkS")
			(effects
				(font
					(size 0.7 0.7)
					(thickness 0.15)
				)
				(justify left bottom)
			)
		)
		(property "Value" "C_4n7_0402"
			(at 0 1.4 180)
			(layer "F.Fab")
			(effects
				(font
					(size 0.7 0.7)
					(thickness 0.15)
				)
				(justify left bottom)
			)
		)
		(property "Description" " "
			(at 0 0 180)
			(layer "F.Fab")
			(hide yes)
			(effects
				(font
					(size 1.27 1.27)
					(thickness 0.15)
				)
			)
		)
		(property "Author" "Antmicro"
			(at 237.6984 233.95 0)
			(layer "F.Fab")
			(hide yes)
			(effects
				(font
					(size 1 1)
					(thickness 0.15)
				)
			)
		)
		(property "Dielectric" ""
			(at 237.6984 233.95 0)
			(layer "F.Fab")
			(hide yes)
			(effects
				(font
					(size 1 1)
					(thickness 0.15)
				)
			)
		)
		(property "License" "Apache-2.0"
			(at 237.6984 233.95 0)
			(layer "F.Fab")
			(hide yes)
			(effects
				(font
					(size 1 1)
					(thickness 0.15)
				)
			)
		)
		(property "MPN" "CGA2B3X7S2A472K050BB"
			(at 237.6984 233.95 0)
			(layer "F.Fab")
			(hide yes)
			(effects
				(font
					(size 1 1)
					(thickness 0.15)
				)
			)
		)
		(property "Manufacturer" "TDK"
			(at 237.6984 233.95 0)
			(layer "F.Fab")
			(hide yes)
			(effects
				(font
					(size 1 1)
					(thickness 0.15)
				)
			)
		)
		(property "Val" "4n7"
			(at 237.6984 233.95 0)
			(layer "F.Fab")
			(hide yes)
			(effects
				(font
					(size 1 1)
					(thickness 0.15)
				)
			)
		)
		(property "Voltage" ""
			(at 237.6984 233.95 0)
			(layer "F.Fab")
			(hide yes)
			(effects
				(font
					(size 1 1)
					(thickness 0.15)
				)
			)
		)
		(sheetname "Supply")
		(sheetfile "supply.kicad_sch")
		(attr smd)
		(fp_rect
			(start -0.94 -0.47)
			(end 0.94 0.47)
			(stroke
				(width 0.05)
				(type solid)
			)
			(fill no)
			(layer "F.CrtYd")
		)
		(fp_rect
			(start -0.499 -0.249)
			(end 0.499 0.249)
			(stroke
				(width 0.15)
				(type solid)
			)
			(fill no)
			(layer "F.Fab")
		)
		(pad "1" smd roundrect
			(at -0.484 0 180)
			(size 0.59 0.64)
			(layers "F.Cu" "F.Mask" "F.Paste")
			(roundrect_rratio 0.25)
			(net 41 "Net-(C129-Pad1)")
			(pintype "passive")
		)
		(pad "2" smd roundrect
			(at 0.484 0 180)
			(size 0.59 0.64)
			(layers "F.Cu" "F.Mask" "F.Paste")
			(roundrect_rratio 0.25)
			(net 5 "GND")
			(pintype "passive")
		)
	)
	(footprint "antmicro-footprints:R_0402_1005Metric"
		(layer "F.Cu")
		(at 118.8492 117.975)
		(descr "Resistor SMD 0402")
		(tags "resistor SMD 0402")
		(property "Reference" "R95"
			(at -0.9492 -1.475 0)
			(layer "F.SilkS")
			(effects
				(font
					(size 0.7 0.7)
					(thickness 0.15)
				)
				(justify left bottom)
			)
		)
		(property "Value" "R_16k9_0402"
			(at 0 1.4 0)
			(layer "F.Fab")
			(effects
				(font
					(size 0.7 0.7)
					(thickness 0.15)
				)
				(justify left bottom)
			)
		)
		(property "Description" "16k9 resistor in 0402 package with 1% tolerance"
			(at 0 0 0)
			(layer "F.Fab")
			(hide yes)
			(effects
				(font
					(size 1.27 1.27)
					(thickness 0.15)
				)
			)
		)
		(property "Author" "Antmicro"
			(at 0 0 0)
			(layer "F.Fab")
			(hide yes)
			(effects
				(font
					(size 1 1)
					(thickness 0.15)
				)
			)
		)
		(property "License" "Apache-2.0"
			(at 0 0 0)
			(layer "F.Fab")
			(hide yes)
			(effects
				(font
					(size 1 1)
					(thickness 0.15)
				)
			)
		)
		(property "MPN" "CR0402-FX-1692GLF"
			(at 0 0 0)
			(layer "F.Fab")
			(hide yes)
			(effects
				(font
					(size 1 1)
					(thickness 0.15)
				)
			)
		)
		(property "Manufacturer" "Bourns"
			(at 0 0 0)
			(layer "F.Fab")
			(hide yes)
			(effects
				(font
					(size 1 1)
					(thickness 0.15)
				)
			)
		)
		(property "Tolerance" "1%"
			(at 0 0 0)
			(layer "F.Fab")
			(hide yes)
			(effects
				(font
					(size 1 1)
					(thickness 0.15)
				)
			)
		)
		(property "Val" "16k9"
			(at 0 0 0)
			(layer "F.Fab")
			(hide yes)
			(effects
				(font
					(size 1 1)
					(thickness 0.15)
				)
			)
		)
		(sheetname "Supply")
		(sheetfile "supply.kicad_sch")
		(attr smd)
		(fp_rect
			(start -0.93 -0.47)
			(end 0.93 0.47)
			(stroke
				(width 0.05)
				(type solid)
			)
			(fill no)
			(layer "F.CrtYd")
		)
		(fp_rect
			(start -0.5 -0.25)
			(end 0.5 0.25)
			(stroke
				(width 0.15)
				(type solid)
			)
			(fill no)
			(layer "F.Fab")
		)
		(pad "1" smd roundrect
			(at -0.485 0)
			(size 0.59 0.64)
			(layers "F.Cu" "F.Mask" "F.Paste")
			(roundrect_rratio 0.25)
			(net 40 "Net-(IC2-COMP)")
			(pintype "passive")
		)
		(pad "2" smd roundrect
			(at 0.485 0)
			(size 0.59 0.64)
			(layers "F.Cu" "F.Mask" "F.Paste")
			(roundrect_rratio 0.25)
			(net 41 "Net-(C129-Pad1)")
			(pintype "passive")
		)
	)
	(footprint "antmicro-footprints:LED_0603_1608Metric_G"
		(layer "F.Cu")
		(at 190.639171 121.074485)
		(descr "LED SMD 0603 Green")
		(tags "LED SMD 0603 Green")
		(property "Reference" "PWR1"
			(at -0.639171 -2.074485 0)
			(layer "F.SilkS")
			(effects
				(font
					(size 0.7 0.7)
					(thickness 0.15)
				)
				(justify left bottom)
			)
		)
		(property "Value" "LED_G_0603_KP-1608CGCK"
			(at 0 1.6 0)
			(layer "F.Fab")
			(effects
				(font
					(size 0.7 0.7)
					(thickness 0.15)
				)
				(justify left bottom)
			)
		)
		(property "Author" "Antmicro"
			(at 0 0 0)
			(layer "F.Fab")
			(hide yes)
			(effects
				(font
					(size 1 1)
					(thickness 0.15)
				)
			)
		)
		(property "License" "Apache-2.0"
			(at 0 0 0)
			(layer "F.Fab")
			(hide yes)
			(effects
				(font
					(size 1 1)
					(thickness 0.15)
				)
			)
		)
		(property "MPN" "KP-1608CGCK"
			(at 0 0 0)
			(layer "F.Fab")
			(hide yes)
			(effects
				(font
					(size 1 1)
					(thickness 0.15)
				)
			)
		)
		(property "Manufacturer" "Kingbright"
			(at 0 0 0)
			(layer "F.Fab")
			(hide yes)
			(effects
				(font
					(size 1 1)
					(thickness 0.15)
				)
			)
		)
		(sheetname "Supply")
		(sheetfile "supply.kicad_sch")
		(attr smd)
		(fp_line
			(start -0.27 -0.35)
			(end 0.27 -0.35)
			(stroke
				(width 0.15)
				(type solid)
			)
			(layer "F.SilkS")
		)
		(fp_line
			(start -0.27 0.351)
			(end 0.27 0.351)
			(stroke
				(width 0.15)
				(type solid)
			)
			(layer "F.SilkS")
		)
		(fp_line
			(start -0.106328 -0.200008)
			(end -0.106328 0.199992)
			(stroke
				(width 0.1)
				(type solid)
			)
			(layer "F.SilkS")
		)
		(fp_line
			(start -0.106328 -0.200008)
			(end 0.093672 -8e-06)
			(stroke
				(width 0.1)
				(type solid)
			)
			(layer "F.SilkS")
		)
		(fp_line
			(start -0.106328 -8e-06)
			(end -0.29 0)
			(stroke
				(width 0.1)
				(type solid)
			)
			(layer "F.SilkS")
		)
		(fp_line
			(start 0.093672 -0.200008)
			(end 0.093672 0.199992)
			(stroke
				(width 0.1)
				(type solid)
			)
			(layer "F.SilkS")
		)
		(fp_line
			(start 0.093672 -8e-06)
			(end -0.106328 0.199992)
			(stroke
				(width 0.1)
				(type solid)
			)
			(layer "F.SilkS")
		)
		(fp_line
			(start 0.093672 -8e-06)
			(end 0.293672 -8e-06)
			(stroke
				(width 0.1)
				(type solid)
			)
			(layer "F.SilkS")
		)
		(fp_line
			(start 1.25 0.32)
			(end 1.25 -0.32)
			(stroke
				(width 0.15)
				(type solid)
			)
			(layer "F.SilkS")
		)
		(fp_rect
			(start 1.26 0.65)
			(end -1.26 -0.65)
			(stroke
				(width 0.05)
				(type solid)
			)
			(fill no)
			(layer "F.CrtYd")
		)
		(fp_line
			(start -0.599 0)
			(end -0.201 0)
			(stroke
				(width 0.15)
				(type solid)
			)
			(layer "F.Fab")
		)
		(fp_line
			(start -0.201 -0.2)
			(end -0.201 0)
			(stroke
				(width 0.15)
				(type solid)
			)
			(layer "F.Fab")
		)
		(fp_line
			(start -0.201 0)
			(end -0.201 0.202)
			(stroke
				(width 0.15)
				(type solid)
			)
			(layer "F.Fab")
		)
		(fp_line
			(start -0.201 0.202)
			(end 0.101 0)
			(stroke
				(width 0.15)
				(type solid)
			)
			(layer "F.Fab")
		)
		(fp_line
			(start 0.101 0)
			(end -0.201 -0.2)
			(stroke
				(width 0.15)
				(type solid)
			)
			(layer "F.Fab")
		)
		(fp_line
			(start 0.199 -0.2)
			(end 0.199 -0.1)
			(stroke
				(width 0.15)
				(type solid)
			)
			(layer "F.Fab")
		)
		(fp_line
			(start 0.199 0)
			(end 0.597 0)
			(stroke
				(width 0.15)
				(type solid)
			)
			(layer "F.Fab")
		)
		(fp_line
			(start 0.199 0.202)
			(end 0.199 -0.1)
			(stroke
				(width 0.15)
				(type solid)
			)
			(layer "F.Fab")
		)
		(fp_rect
			(start -0.848 -0.4)
			(end 0.85 0.402)
			(stroke
				(width 0.15)
				(type solid)
			)
			(fill no)
			(layer "F.Fab")
		)
		(pad "1" smd rect
			(at -0.75 0 180)
			(size 0.8 0.8)
			(layers "F.Cu" "F.Mask" "F.Paste")
			(net 459 "3V3_SYS")
			(pinfunction "1")
			(pintype "passive")
		)
		(pad "2" smd rect
			(at 0.75 0 180)
			(size 0.8 0.8)
			(layers "F.Cu" "F.Mask" "F.Paste")
			(net 229 "Net-(PWR1-Pad2)")
			(pinfunction "2")
			(pintype "passive")
		)
	)
)
